FILE_TYPE = CONNECTIVITY;
{Allegro Design Entry HDL 16.6-p007 (v16-6-112F) 10/10/2012}
"PAGE_NUMBER" = 163;
0"NC";
1"GND\g";
2"GND\g";
3"P3V3_STBY\g";
4"P3V3_STBY\g";
5"GND\g";
6"PVCCIO_CPU1\g";
7"PVCCIO_CPU1\g";
8"SMB_CPU1_PE_HP_GTL_R_SDA";
9"SMB_CPU1_PE_HP_GTL_R_SCL";
10"SMB_PEHPCPU1_STBY_LVC3_R_SCL";
11"SMB_CPU1_PE_HP_GTL_SCL";
12"SMB_CPU1_PE_HP_GTL_SDA";
13"SMB_PEHPCPU1_STBY_LVC3_SCL";
14"SMB_PEHPCPU1_STBY_LVC3_SDA";
15"TP_SMB_PEHPCPU1_EN";
16"SMB_PEHPCPU1_STBY_LVC3_R_SDA";
%"CAP_A"
"1","(-1800,3850)","0","dev_discrete","I10";
;
CDS_SEC"1"
LOCATION"C9M8"
PART_NUMBER"A36096-030"
VALUE"0.1UF"
TOLERANCE"10%"
PACK_TYPE"0402V"
VOLTAGE"16V"
MATERIAL"X7R"
CDS_LOCATION"C9M8"
CDS_LIB"dev_discrete"
SEC"1"
SEC_TYPE"0402V"
ROOM"SMB_PE_HP_CPU1";
"B"
$PN"2"1;
"A"
$PN"1"7;
%"GND"
"1","(-1800,3600)","0","mstr_symbols","I11";
;
ROOM"P2V5_LAN_AUX_VR"
BOM_COST"NT_BASE_VRD"
SIZE"1B"
CDS_LIB"mstr_symbols"
VOLTAGE"0"
BODY_TYPE"PLUMBING"
HDL_POWER"GND";
"A\NAC"1;
%"CAP_A"
"1","(-1150,3850)","2","dev_discrete","I12";
;
CDS_SEC"1"
PACK_TYPE"0402V"
PART_NUMBER"A36096-030"
LOCATION"C9M7"
VALUE"0.1UF"
TOLERANCE"10%"
VOLTAGE"16V"
MATERIAL"X7R"
SEC_TYPE"0402V"
SEC"1"
CDS_LIB"dev_discrete"
CDS_LOCATION"C9M7"
ROOM"SMB_PE_HP_CPU1";
"B"
$PN"2"2;
"A"
$PN"1"3;
%"GND"
"1","(-1150,3600)","0","mstr_symbols","I13";
;
ROOM"P2V5_LAN_AUX_VR"
BOM_COST"NT_BASE_VRD"
SIZE"1B"
CDS_LIB"mstr_symbols"
VOLTAGE"0"
BODY_TYPE"PLUMBING"
HDL_POWER"GND";
"A\NAC"2;
%"RES"
"2","(-600,3650)","2","mstr_discrete","I15";
;
CDS_SEC"1"
PACK_TYPE"0402"
MATERIAL"CHIP"
TOLERANCE"1%"
WATTAGE"1/16W"
VALUE"2.0K"
LOCATION"R9M17"
PART_NUMBER"G21796-001"
ROOM"SMB_PE_HP_CPU1"
CDS_LIB"mstr_discrete"
SEC_TYPE"0402"
SEC"1"
CDS_LOCATION"R9M17";
"A"
$PN"1"4;
"B"
$PN"2"10;
%"RES"
"2","(-450,3650)","0","mstr_discrete","I16";
;
CDS_SEC"1"
WATTAGE"1/16W"
PACK_TYPE"0402"
TOLERANCE"1%"
PART_NUMBER"G21796-001"
MATERIAL"CHIP"
LOCATION"R9M16"
VALUE"2.0K"
ROOM"SMB_PE_HP_CPU1"
SEC_TYPE"0402"
CDS_LIB"mstr_discrete"
SEC"1"
CDS_LOCATION"R9M16";
"A"
$PN"1"4;
"B"
$PN"2"16;
%"RES"
"1","(-3800,3300)","0","mstr_discrete","I2";
;
CDS_SEC"1"
WATTAGE"1/16W"
MATERIAL"CHIP"
PACK_TYPE"0402"
TOLERANCE"1%"
VALUE"10.0"
PART_NUMBER"G21796-066"
LOCATION"R6N8"
ROOM"CPU1"
SEC_TYPE"0402"
CDS_LIB"mstr_discrete"
SEC"1"
CDS_LOCATION"R6N8";
"B"
$PN"2"9;
"A"
$PN"1"11;
%"RES"
"1","(-50,3300)","0","mstr_discrete","I20";
;
CDS_SEC"1"
TOLERANCE"1%"
LOCATION"R9M14"
PART_NUMBER"G21796-173"
PACK_TYPE"0402"
VALUE"20.0"
WATTAGE"1/16W"
MATERIAL"CHIP"
SEC_TYPE"0402"
SEC"1"
ROOM"SMB_PE_HP_CPU1"
CDS_LIB"mstr_discrete"
CDS_LOCATION"R9M14";
"B"
$PN"2"13;
"A"
$PN"1"10;
%"RES"
"1","(200,3250)","0","mstr_discrete","I21";
;
CDS_SEC"1"
WATTAGE"1/16W"
LOCATION"R9M13"
PART_NUMBER"G21796-173"
MATERIAL"CHIP"
VALUE"20.0"
TOLERANCE"1%"
PACK_TYPE"0402"
SEC_TYPE"0402"
SEC"1"
ROOM"SMB_PE_HP_CPU1"
CDS_LIB"mstr_discrete"
CDS_LOCATION"R9M13";
"B"
$PN"2"14;
"A"
$PN"1"16;
%"P3V3_STBY"
"1","(-1100,4150)","0","mstr_symbols","I26";
;
VOLTAGE"3.3V"
CDS_LIB"mstr_symbols"
SIZE"1B"
BODY_TYPE"PLUMBING"
HDL_POWER"P3V3_STBY";
"G\NAC"3;
%"P3V3_STBY"
"1","(-525,4050)","0","mstr_symbols","I27";
;
CDS_LIB"mstr_symbols"
SIZE"1B"
VOLTAGE"3.3V"
BODY_TYPE"PLUMBING"
HDL_POWER"P3V3_STBY";
"G\NAC"4;
%"TCA9517DGKR-GP"
"1","(-1475,3275)","0","w_hdl","I28";
;
CDS_SEC"1"
CDS_LOCATION"U1B2"
LOCATION"U1B2"
VALUE"TCA9517DGKR-GP"
PACK_TYPE"DISCRET-G8"
SEC"1"
SEC_TYPE"DISCRET-G8"
CDS_LMAN_SYM_OUTLINE"-175,175,175,-175"
CDS_LIB"w_hdl"
PART_NUMBER"071.09517.0009";
"EN"
$PN"5"15;
"SDAB"
$PN"6"16;
"SCLB"
$PN"7"10;
"VCCB"
$PN"8"3;
"GND"
$PN"4"5;
"SDAA"
$PN"3"8;
"SCLA"
$PN"2"9;
"VCCA"
$PN"1"7;
%"GND"
"1","(-1900,3100)","0","mstr_symbols","I29";
;
ROOM"P2V5_LAN_AUX_VR"
BOM_COST"NT_BASE_VRD"
SIZE"1B"
CDS_LIB"mstr_symbols"
VOLTAGE"0"
BODY_TYPE"PLUMBING"
HDL_POWER"GND";
"A\NAC"5;
%"RES"
"1","(-3275,3250)","0","mstr_discrete","I3";
;
CDS_SEC"1"
WATTAGE"1/16W"
MATERIAL"CHIP"
PACK_TYPE"0402"
TOLERANCE"1%"
VALUE"10.0"
PART_NUMBER"G21796-066"
LOCATION"R6N9"
ROOM"CPU1"
SEC_TYPE"0402"
CDS_LIB"mstr_discrete"
SEC"1"
CDS_LOCATION"R6N9";
"B"
$PN"2"8;
"A"
$PN"1"12;
%"RES"
"2","(-2200,3650)","0","mstr_discrete","I6";
;
CDS_SEC"1"
WATTAGE"1/16W"
MATERIAL"CHIP"
PACK_TYPE"0402"
TOLERANCE"1.0%"
VALUE"240"
PART_NUMBER"G21796-294"
LOCATION"R9M18"
ROOM"SMB_PE_HP_CPU1"
SEC_TYPE"0402"
CDS_LIB"mstr_discrete"
SEC"1"
CDS_LOCATION"R9M18";
"A"
$PN"1"6;
"B"
$PN"2"8;
%"RES"
"2","(-2325,3650)","2","mstr_discrete","I7";
;
CDS_SEC"1"
PACK_TYPE"0402"
WATTAGE"1/16W"
MATERIAL"CHIP"
TOLERANCE"1.0%"
VALUE"240"
LOCATION"R9M19"
PART_NUMBER"G21796-294"
ROOM"SMB_PE_HP_CPU1"
SEC_TYPE"0402"
CDS_LIB"mstr_discrete"
SEC"1"
CDS_LOCATION"R9M19";
"A"
$PN"1"6;
"B"
$PN"2"9;
%"PVCCIO_CPU1"
"1","(-2250,4000)","0","mstr_symbols","I8";
;
CDS_LIB"mstr_symbols"
VOLTAGE"1.1V"
BODY_TYPE"PLUMBING"
HDL_POWER"PVCCIO_CPU1";
"G\NAC"6;
%"PVCCIO_CPU1"
"1","(-1850,4150)","0","mstr_symbols","I9";
;
CDS_LIB"mstr_symbols"
VOLTAGE"1.1V"
BODY_TYPE"PLUMBING"
HDL_POWER"PVCCIO_CPU1";
"G\NAC"7;
END.
